# S9S_MB_2U (Grand Teton) — schematic netlist excerpt (pin names and nets, part order shuffled) for the footprints in the layout excerpt that follows; sources: Cadence DE-HDL packaged netlist, KiCad conversion of 03242023_DA0F0TMBIJ0_F0T_Motherboard_J_brd_V01_OCP.brd

C59  Q_CAP  2.2UF 6.3V 20% X6S  pkg C0402  page 101 : A = P3V3_AUX ; B = GND
R701  Q_RES  10K 1% EMPTY  pkg 0402LF  page 130 : A = RST_PLD_CPU1_DRAM_CD_N ; B = GND

(kicad_pcb
	(version 20260206)
	(generator "pcbnew")
	(generator_version "10.0")
	(general
		(thickness 1.6)
		(legacy_teardrops no)
	)
	(paper "A4")
	(title_block
		(title "03242023_DA0F0TMBIJ0_F0T_Motherboard_J_brd_V01_OCP.brd")
		(comment 1 "Grand Teton / footprints 5325-5326 of 6105")
	)
	(layers
		(0 "F.Cu" signal "TOP")
		(4 "In1.Cu" signal "GND")
		(6 "In2.Cu" signal "IN1")
		(8 "In3.Cu" signal "GND1")
		(10 "In4.Cu" signal "IN2")
		(12 "In5.Cu" signal "GND2")
		(14 "In6.Cu" signal "IN3")
		(16 "In7.Cu" signal "GND3")
		(18 "In8.Cu" signal "VCC")
		(20 "In9.Cu" signal "VCC1")
		(22 "In10.Cu" signal "GND4")
		(24 "In11.Cu" signal "IN4")
		(26 "In12.Cu" signal "GND5")
		(28 "In13.Cu" signal "IN5")
		(30 "In14.Cu" signal "GND6")
		(32 "In15.Cu" signal "IN6")
		(34 "In16.Cu" signal "GND7")
		(2 "B.Cu" signal "BOTTOM")
		(9 "F.Adhes" user "F.Adhesive")
		(11 "B.Adhes" user "B.Adhesive")
		(13 "F.Paste" user "Package Geometry/Pastemask Top")
		(15 "B.Paste" user "Package Geometry/Pastemask Bottom")
		(5 "F.SilkS" user "Ref Des/Silkscreen Top")
		(7 "B.SilkS" user "Ref Des/Silkscreen Bottom")
		(1 "F.Mask" user "Board Geometry/Soldermask Top")
		(3 "B.Mask" user "Board Geometry/Soldermask Bottom")
		(17 "Dwgs.User" user "User.Drawings")
		(19 "Cmts.User" user "User.Comments")
		(21 "Eco1.User" user "User.Eco1")
		(23 "Eco2.User" user "User.Eco2")
		(25 "Edge.Cuts" user "Board Geometry/Outline")
		(27 "Margin" user)
		(31 "F.CrtYd" user "Package Geometry/Place Bound Top")
		(29 "B.CrtYd" user "Package Geometry/Place Bound Bottom")
		(35 "F.Fab" user "Ref Des/Assembly Top")
		(33 "B.Fab" user "Ref Des/Assembly Bottom")
	)
	(footprint ""
		(layer "B.Cu")
		(at 45.872146 -319.268856 180)
		(property "Reference" "C59"
			(at 0 0 0)
			(layer "B.SilkS")
			(hide yes)
			(effects
				(font
					(size 1.27 1.27)
				)
				(justify mirror)
			)
		)
		(property "Value" ""
			(at 0 0 0)
			(layer "B.Fab")
			(effects
				(font
					(size 1.27 1.27)
				)
				(justify mirror)
			)
		)
		(duplicate_pad_numbers_are_jumpers no)
		(fp_line
			(start 0.7874 0.4064)
			(end 0.7874 -0.4064)
			(stroke
				(width 0.1524)
				(type default)
			)
			(layer "B.SilkS")
		)
		(fp_line
			(start 0.7874 -0.4064)
			(end -0.7874 -0.4064)
			(stroke
				(width 0.1524)
				(type default)
			)
			(layer "B.SilkS")
		)
		(fp_line
			(start -0.7874 0.4064)
			(end 0.7874 0.4064)
			(stroke
				(width 0.1524)
				(type default)
			)
			(layer "B.SilkS")
		)
		(fp_line
			(start -0.7874 -0.4064)
			(end -0.7874 0.4064)
			(stroke
				(width 0.1524)
				(type default)
			)
			(layer "B.SilkS")
		)
		(fp_line
			(start 0.67945 0.3048)
			(end 0.67945 -0.305054)
			(stroke
				(width 0.1)
				(type default)
			)
			(layer "B.Fab")
		)
		(fp_line
			(start 0.67945 -0.305054)
			(end 0.12065 -0.305054)
			(stroke
				(width 0.1)
				(type default)
			)
			(layer "B.Fab")
		)
		(fp_line
			(start 0.12065 0.3048)
			(end 0.67945 0.3048)
			(stroke
				(width 0.1)
				(type default)
			)
			(layer "B.Fab")
		)
		(fp_line
			(start 0.12065 0.2794)
			(end 0.12065 0.3048)
			(stroke
				(width 0.1)
				(type default)
			)
			(layer "B.Fab")
		)
		(fp_line
			(start 0.12065 -0.2794)
			(end -0.12065 -0.2794)
			(stroke
				(width 0.1)
				(type default)
			)
			(layer "B.Fab")
		)
		(fp_line
			(start 0.12065 -0.305054)
			(end 0.12065 -0.2794)
			(stroke
				(width 0.1)
				(type default)
			)
			(layer "B.Fab")
		)
		(fp_line
			(start -0.120396 0.3048)
			(end -0.120396 0.2794)
			(stroke
				(width 0.1)
				(type default)
			)
			(layer "B.Fab")
		)
		(fp_line
			(start -0.120396 0.2794)
			(end 0.12065 0.2794)
			(stroke
				(width 0.1)
				(type default)
			)
			(layer "B.Fab")
		)
		(fp_line
			(start -0.12065 -0.2794)
			(end -0.12065 -0.3048)
			(stroke
				(width 0.1)
				(type default)
			)
			(layer "B.Fab")
		)
		(fp_line
			(start -0.12065 -0.3048)
			(end -0.67945 -0.3048)
			(stroke
				(width 0.1)
				(type default)
			)
			(layer "B.Fab")
		)
		(fp_line
			(start -0.67945 0.3048)
			(end -0.120396 0.3048)
			(stroke
				(width 0.1)
				(type default)
			)
			(layer "B.Fab")
		)
		(fp_line
			(start -0.67945 -0.3048)
			(end -0.67945 0.3048)
			(stroke
				(width 0.1)
				(type default)
			)
			(layer "B.Fab")
		)
		(pad "1" smd circle
			(at 0.40005 0)
			(size 0 0)
			(layers "B.Cu" "B.Mask" "B.Paste")
			(net "P3V3_AUX")
		)
		(pad "2" smd circle
			(at -0.40005 0)
			(size 0 0)
			(layers "B.Cu" "B.Mask" "B.Paste")
			(net "GND")
		)
	)
	(footprint ""
		(layer "B.Cu")
		(at 24.327866 -193.152776 -90)
		(property "Reference" "R701"
			(at 0 0 90)
			(layer "B.SilkS")
			(hide yes)
			(effects
				(font
					(size 1.27 1.27)
				)
				(justify mirror)
			)
		)
		(property "Value" ""
			(at 0 0 90)
			(layer "B.Fab")
			(effects
				(font
					(size 1.27 1.27)
				)
				(justify mirror)
			)
		)
		(duplicate_pad_numbers_are_jumpers no)
		(fp_line
			(start -0.7874 0.4064)
			(end 0.7874 0.4064)
			(stroke
				(width 0.1524)
				(type default)
			)
			(layer "B.SilkS")
		)
		(fp_line
			(start 0.7874 0.4064)
			(end 0.7874 -0.4064)
			(stroke
				(width 0.1524)
				(type default)
			)
			(layer "B.SilkS")
		)
		(fp_line
			(start -0.7874 -0.4064)
			(end -0.7874 0.4064)
			(stroke
				(width 0.1524)
				(type default)
			)
			(layer "B.SilkS")
		)
		(fp_line
			(start 0.7874 -0.4064)
			(end -0.7874 -0.4064)
			(stroke
				(width 0.1524)
				(type default)
			)
			(layer "B.SilkS")
		)
		(fp_line
			(start -0.67945 0.3048)
			(end -0.120396 0.3048)
			(stroke
				(width 0.1)
				(type default)
			)
			(layer "B.Fab")
		)
		(fp_line
			(start -0.120396 0.3048)
			(end -0.120396 0.2794)
			(stroke
				(width 0.1)
				(type default)
			)
			(layer "B.Fab")
		)
		(fp_line
			(start 0.12065 0.3048)
			(end 0.67945 0.3048)
			(stroke
				(width 0.1)
				(type default)
			)
			(layer "B.Fab")
		)
		(fp_line
			(start 0.67945 0.3048)
			(end 0.67945 -0.305054)
			(stroke
				(width 0.1)
				(type default)
			)
			(layer "B.Fab")
		)
		(fp_line
			(start -0.120396 0.2794)
			(end 0.12065 0.2794)
			(stroke
				(width 0.1)
				(type default)
			)
			(layer "B.Fab")
		)
		(fp_line
			(start 0.12065 0.2794)
			(end 0.12065 0.3048)
			(stroke
				(width 0.1)
				(type default)
			)
			(layer "B.Fab")
		)
		(fp_line
			(start -0.12065 -0.2794)
			(end -0.12065 -0.3048)
			(stroke
				(width 0.1)
				(type default)
			)
			(layer "B.Fab")
		)
		(fp_line
			(start 0.12065 -0.2794)
			(end -0.12065 -0.2794)
			(stroke
				(width 0.1)
				(type default)
			)
			(layer "B.Fab")
		)
		(fp_line
			(start -0.67945 -0.3048)
			(end -0.67945 0.3048)
			(stroke
				(width 0.1)
				(type default)
			)
			(layer "B.Fab")
		)
		(fp_line
			(start -0.12065 -0.3048)
			(end -0.67945 -0.3048)
			(stroke
				(width 0.1)
				(type default)
			)
			(layer "B.Fab")
		)
		(fp_line
			(start 0.12065 -0.305054)
			(end 0.12065 -0.2794)
			(stroke
				(width 0.1)
				(type default)
			)
			(layer "B.Fab")
		)
		(fp_line
			(start 0.67945 -0.305054)
			(end 0.12065 -0.305054)
			(stroke
				(width 0.1)
				(type default)
			)
			(layer "B.Fab")
		)
		(pad "1" smd circle
			(at 0.40005 0 90)
			(size 0 0)
			(layers "B.Cu" "B.Mask" "B.Paste")
			(net "RST_PLD_CPU1_DRAM_CD_N")
		)
		(pad "2" smd circle
			(at -0.40005 0 90)
			(size 0 0)
			(layers "B.Cu" "B.Mask" "B.Paste")
			(net "GND")
		)
	)
)
